(kicad_pcb
	(version 20260206)
	(generator "pcbnew")
	(generator_version "10.0")
	(general
		(thickness 1.6)
		(legacy_teardrops no)
	)
	(paper "A4")
	(title_block
		(title "9052_F0T_PDB_Converter_Brick_F_V03_1208_1600_OCP.brd")
		(comment 1 "Grand Teton / footprints 481-486 of 578")
	)
	(layers
		(0 "F.Cu" signal "TOP")
		(4 "In1.Cu" signal "GND")
		(6 "In2.Cu" signal "IN1")
		(8 "In3.Cu" signal "GND1")
		(10 "In4.Cu" signal "VCC")
		(12 "In5.Cu" signal "VCC1")
		(14 "In6.Cu" signal "GND2")
		(16 "In7.Cu" signal "IN2")
		(18 "In8.Cu" signal "GND3")
		(2 "B.Cu" signal "BOTTOM")
		(9 "F.Adhes" user "F.Adhesive")
		(11 "B.Adhes" user "B.Adhesive")
		(13 "F.Paste" user "Package Geometry/Pastemask Top")
		(15 "B.Paste" user "Package Geometry/Pastemask Bottom")
		(5 "F.SilkS" user "Ref Des/Silkscreen Top")
		(7 "B.SilkS" user "Ref Des/Silkscreen Bottom")
		(1 "F.Mask" user "Board Geometry/Soldermask Top")
		(3 "B.Mask" user "Board Geometry/Soldermask Bottom")
		(17 "Dwgs.User" user "User.Drawings")
		(19 "Cmts.User" user "User.Comments")
		(21 "Eco1.User" user "User.Eco1")
		(23 "Eco2.User" user "User.Eco2")
		(25 "Edge.Cuts" user "Board Geometry/Outline")
		(27 "Margin" user)
		(31 "F.CrtYd" user "Package Geometry/Place Bound Top")
		(29 "B.CrtYd" user "Package Geometry/Place Bound Bottom")
		(35 "F.Fab" user "Ref Des/Assembly Top")
		(33 "B.Fab" user "Ref Des/Assembly Bottom")
	)
	(footprint ""
		(layer "B.Cu")
		(at 56.850026 -114.046 90)
		(property "Reference" "C60"
			(at 0 0 90)
			(layer "B.SilkS")
			(hide yes)
			(effects
				(font
					(size 1.27 1.27)
				)
				(justify mirror)
			)
		)
		(property "Value" ""
			(at 0 0 90)
			(layer "B.Fab")
			(effects
				(font
					(size 1.27 1.27)
				)
				(justify mirror)
			)
		)
		(duplicate_pad_numbers_are_jumpers no)
		(fp_line
			(start 0.7874 -0.4064)
			(end -0.7874 -0.4064)
			(stroke
				(width 0.1524)
				(type default)
			)
			(layer "B.SilkS")
		)
		(fp_line
			(start -0.7874 -0.4064)
			(end -0.7874 0.4064)
			(stroke
				(width 0.1524)
				(type default)
			)
			(layer "B.SilkS")
		)
		(fp_line
			(start 0.7874 0.4064)
			(end 0.7874 -0.4064)
			(stroke
				(width 0.1524)
				(type default)
			)
			(layer "B.SilkS")
		)
		(fp_line
			(start -0.7874 0.4064)
			(end 0.7874 0.4064)
			(stroke
				(width 0.1524)
				(type default)
			)
			(layer "B.SilkS")
		)
		(fp_line
			(start 0.67945 -0.305054)
			(end 0.12065 -0.305054)
			(stroke
				(width 0.1)
				(type default)
			)
			(layer "B.Fab")
		)
		(fp_line
			(start 0.12065 -0.305054)
			(end 0.12065 -0.2794)
			(stroke
				(width 0.1)
				(type default)
			)
			(layer "B.Fab")
		)
		(fp_line
			(start -0.12065 -0.3048)
			(end -0.67945 -0.3048)
			(stroke
				(width 0.1)
				(type default)
			)
			(layer "B.Fab")
		)
		(fp_line
			(start -0.67945 -0.3048)
			(end -0.67945 0.3048)
			(stroke
				(width 0.1)
				(type default)
			)
			(layer "B.Fab")
		)
		(fp_line
			(start 0.12065 -0.2794)
			(end -0.12065 -0.2794)
			(stroke
				(width 0.1)
				(type default)
			)
			(layer "B.Fab")
		)
		(fp_line
			(start -0.12065 -0.2794)
			(end -0.12065 -0.3048)
			(stroke
				(width 0.1)
				(type default)
			)
			(layer "B.Fab")
		)
		(fp_line
			(start 0.12065 0.2794)
			(end 0.12065 0.3048)
			(stroke
				(width 0.1)
				(type default)
			)
			(layer "B.Fab")
		)
		(fp_line
			(start -0.120396 0.2794)
			(end 0.12065 0.2794)
			(stroke
				(width 0.1)
				(type default)
			)
			(layer "B.Fab")
		)
		(fp_line
			(start 0.67945 0.3048)
			(end 0.67945 -0.305054)
			(stroke
				(width 0.1)
				(type default)
			)
			(layer "B.Fab")
		)
		(fp_line
			(start 0.12065 0.3048)
			(end 0.67945 0.3048)
			(stroke
				(width 0.1)
				(type default)
			)
			(layer "B.Fab")
		)
		(fp_line
			(start -0.120396 0.3048)
			(end -0.120396 0.2794)
			(stroke
				(width 0.1)
				(type default)
			)
			(layer "B.Fab")
		)
		(fp_line
			(start -0.67945 0.3048)
			(end -0.120396 0.3048)
			(stroke
				(width 0.1)
				(type default)
			)
			(layer "B.Fab")
		)
		(pad "1" smd circle
			(at 0.40005 0 270)
			(size 0 0)
			(layers "B.Cu" "B.Mask" "B.Paste")
			(net "BRICK_P12V_1_EN_N")
		)
		(pad "2" smd circle
			(at -0.40005 0 270)
			(size 0 0)
			(layers "B.Cu" "B.Mask" "B.Paste")
			(net "GND")
		)
	)
	(footprint ""
		(layer "B.Cu")
		(at 268.986 -36.068 180)
		(property "Reference" "PR11"
			(at 0 0 0)
			(layer "B.SilkS")
			(hide yes)
			(effects
				(font
					(size 1.27 1.27)
				)
				(justify mirror)
			)
		)
		(property "Value" ""
			(at 0 0 0)
			(layer "B.Fab")
			(effects
				(font
					(size 1.27 1.27)
				)
				(justify mirror)
			)
		)
		(duplicate_pad_numbers_are_jumpers no)
		(fp_line
			(start 0.7874 0.4064)
			(end 0.7874 -0.4064)
			(stroke
				(width 0.1524)
				(type default)
			)
			(layer "B.SilkS")
		)
		(fp_line
			(start 0.7874 -0.4064)
			(end -0.7874 -0.4064)
			(stroke
				(width 0.1524)
				(type default)
			)
			(layer "B.SilkS")
		)
		(fp_line
			(start -0.7874 0.4064)
			(end 0.7874 0.4064)
			(stroke
				(width 0.1524)
				(type default)
			)
			(layer "B.SilkS")
		)
		(fp_line
			(start -0.7874 -0.4064)
			(end -0.7874 0.4064)
			(stroke
				(width 0.1524)
				(type default)
			)
			(layer "B.SilkS")
		)
		(fp_line
			(start 0.67945 0.3048)
			(end 0.67945 -0.305054)
			(stroke
				(width 0.1)
				(type default)
			)
			(layer "B.Fab")
		)
		(fp_line
			(start 0.67945 -0.305054)
			(end 0.12065 -0.305054)
			(stroke
				(width 0.1)
				(type default)
			)
			(layer "B.Fab")
		)
		(fp_line
			(start 0.12065 0.3048)
			(end 0.67945 0.3048)
			(stroke
				(width 0.1)
				(type default)
			)
			(layer "B.Fab")
		)
		(fp_line
			(start 0.12065 0.2794)
			(end 0.12065 0.3048)
			(stroke
				(width 0.1)
				(type default)
			)
			(layer "B.Fab")
		)
		(fp_line
			(start 0.12065 -0.2794)
			(end -0.12065 -0.2794)
			(stroke
				(width 0.1)
				(type default)
			)
			(layer "B.Fab")
		)
		(fp_line
			(start 0.12065 -0.305054)
			(end 0.12065 -0.2794)
			(stroke
				(width 0.1)
				(type default)
			)
			(layer "B.Fab")
		)
		(fp_line
			(start -0.120396 0.3048)
			(end -0.120396 0.2794)
			(stroke
				(width 0.1)
				(type default)
			)
			(layer "B.Fab")
		)
		(fp_line
			(start -0.120396 0.2794)
			(end 0.12065 0.2794)
			(stroke
				(width 0.1)
				(type default)
			)
			(layer "B.Fab")
		)
		(fp_line
			(start -0.12065 -0.2794)
			(end -0.12065 -0.3048)
			(stroke
				(width 0.1)
				(type default)
			)
			(layer "B.Fab")
		)
		(fp_line
			(start -0.12065 -0.3048)
			(end -0.67945 -0.3048)
			(stroke
				(width 0.1)
				(type default)
			)
			(layer "B.Fab")
		)
		(fp_line
			(start -0.67945 0.3048)
			(end -0.120396 0.3048)
			(stroke
				(width 0.1)
				(type default)
			)
			(layer "B.Fab")
		)
		(fp_line
			(start -0.67945 -0.3048)
			(end -0.67945 0.3048)
			(stroke
				(width 0.1)
				(type default)
			)
			(layer "B.Fab")
		)
		(pad "1" smd circle
			(at 0.40005 0)
			(size 0 0)
			(layers "B.Cu" "B.Mask" "B.Paste")
			(net "GND_FIELD_SIGNAL")
		)
		(pad "2" smd circle
			(at -0.40005 0)
			(size 0 0)
			(layers "B.Cu" "B.Mask" "B.Paste")
			(net "P52V_HS1_CLKIN")
		)
	)
	(footprint ""
		(layer "B.Cu")
		(at 189.611 -84.963)
		(property "Reference" "R127"
			(at 0 0 0)
			(layer "B.SilkS")
			(hide yes)
			(effects
				(font
					(size 1.27 1.27)
				)
				(justify mirror)
			)
		)
		(property "Value" ""
			(at 0 0 0)
			(layer "B.Fab")
			(effects
				(font
					(size 1.27 1.27)
				)
				(justify mirror)
			)
		)
		(duplicate_pad_numbers_are_jumpers no)
		(fp_line
			(start -0.7874 -0.4064)
			(end -0.7874 0.4064)
			(stroke
				(width 0.1524)
				(type default)
			)
			(layer "B.SilkS")
		)
		(fp_line
			(start -0.7874 0.4064)
			(end 0.7874 0.4064)
			(stroke
				(width 0.1524)
				(type default)
			)
			(layer "B.SilkS")
		)
		(fp_line
			(start 0.7874 -0.4064)
			(end -0.7874 -0.4064)
			(stroke
				(width 0.1524)
				(type default)
			)
			(layer "B.SilkS")
		)
		(fp_line
			(start 0.7874 0.4064)
			(end 0.7874 -0.4064)
			(stroke
				(width 0.1524)
				(type default)
			)
			(layer "B.SilkS")
		)
		(fp_line
			(start -0.67945 -0.3048)
			(end -0.67945 0.3048)
			(stroke
				(width 0.1)
				(type default)
			)
			(layer "B.Fab")
		)
		(fp_line
			(start -0.67945 0.3048)
			(end -0.120396 0.3048)
			(stroke
				(width 0.1)
				(type default)
			)
			(layer "B.Fab")
		)
		(fp_line
			(start -0.12065 -0.3048)
			(end -0.67945 -0.3048)
			(stroke
				(width 0.1)
				(type default)
			)
			(layer "B.Fab")
		)
		(fp_line
			(start -0.12065 -0.2794)
			(end -0.12065 -0.3048)
			(stroke
				(width 0.1)
				(type default)
			)
			(layer "B.Fab")
		)
		(fp_line
			(start -0.120396 0.2794)
			(end 0.12065 0.2794)
			(stroke
				(width 0.1)
				(type default)
			)
			(layer "B.Fab")
		)
		(fp_line
			(start -0.120396 0.3048)
			(end -0.120396 0.2794)
			(stroke
				(width 0.1)
				(type default)
			)
			(layer "B.Fab")
		)
		(fp_line
			(start 0.12065 -0.305054)
			(end 0.12065 -0.2794)
			(stroke
				(width 0.1)
				(type default)
			)
			(layer "B.Fab")
		)
		(fp_line
			(start 0.12065 -0.2794)
			(end -0.12065 -0.2794)
			(stroke
				(width 0.1)
				(type default)
			)
			(layer "B.Fab")
		)
		(fp_line
			(start 0.12065 0.2794)
			(end 0.12065 0.3048)
			(stroke
				(width 0.1)
				(type default)
			)
			(layer "B.Fab")
		)
		(fp_line
			(start 0.12065 0.3048)
			(end 0.67945 0.3048)
			(stroke
				(width 0.1)
				(type default)
			)
			(layer "B.Fab")
		)
		(fp_line
			(start 0.67945 -0.305054)
			(end 0.12065 -0.305054)
			(stroke
				(width 0.1)
				(type default)
			)
			(layer "B.Fab")
		)
		(fp_line
			(start 0.67945 0.3048)
			(end 0.67945 -0.305054)
			(stroke
				(width 0.1)
				(type default)
			)
			(layer "B.Fab")
		)
		(pad "1" smd circle
			(at 0.40005 0 180)
			(size 0 0)
			(layers "B.Cu" "B.Mask" "B.Paste")
			(net "SMB_P52V_VPDB_SCL_R")
		)
		(pad "2" smd circle
			(at -0.40005 0 180)
			(size 0 0)
			(layers "B.Cu" "B.Mask" "B.Paste")
			(net "P3V3_AUX")
		)
	)
	(footprint ""
		(layer "B.Cu")
		(at 174.493174 -78.867)
		(property "Reference" "R192"
			(at 0 0 0)
			(layer "B.SilkS")
			(hide yes)
			(effects
				(font
					(size 1.27 1.27)
				)
				(justify mirror)
			)
		)
		(property "Value" ""
			(at 0 0 0)
			(layer "B.Fab")
			(effects
				(font
					(size 1.27 1.27)
				)
				(justify mirror)
			)
		)
		(duplicate_pad_numbers_are_jumpers no)
		(fp_line
			(start -0.7874 -0.4064)
			(end -0.7874 0.4064)
			(stroke
				(width 0.1524)
				(type default)
			)
			(layer "B.SilkS")
		)
		(fp_line
			(start -0.7874 0.4064)
			(end 0.7874 0.4064)
			(stroke
				(width 0.1524)
				(type default)
			)
			(layer "B.SilkS")
		)
		(fp_line
			(start 0.7874 -0.4064)
			(end -0.7874 -0.4064)
			(stroke
				(width 0.1524)
				(type default)
			)
			(layer "B.SilkS")
		)
		(fp_line
			(start 0.7874 0.4064)
			(end 0.7874 -0.4064)
			(stroke
				(width 0.1524)
				(type default)
			)
			(layer "B.SilkS")
		)
		(fp_line
			(start -0.67945 -0.3048)
			(end -0.67945 0.3048)
			(stroke
				(width 0.1)
				(type default)
			)
			(layer "B.Fab")
		)
		(fp_line
			(start -0.67945 0.3048)
			(end -0.120396 0.3048)
			(stroke
				(width 0.1)
				(type default)
			)
			(layer "B.Fab")
		)
		(fp_line
			(start -0.12065 -0.3048)
			(end -0.67945 -0.3048)
			(stroke
				(width 0.1)
				(type default)
			)
			(layer "B.Fab")
		)
		(fp_line
			(start -0.12065 -0.2794)
			(end -0.12065 -0.3048)
			(stroke
				(width 0.1)
				(type default)
			)
			(layer "B.Fab")
		)
		(fp_line
			(start -0.120396 0.2794)
			(end 0.12065 0.2794)
			(stroke
				(width 0.1)
				(type default)
			)
			(layer "B.Fab")
		)
		(fp_line
			(start -0.120396 0.3048)
			(end -0.120396 0.2794)
			(stroke
				(width 0.1)
				(type default)
			)
			(layer "B.Fab")
		)
		(fp_line
			(start 0.12065 -0.305054)
			(end 0.12065 -0.2794)
			(stroke
				(width 0.1)
				(type default)
			)
			(layer "B.Fab")
		)
		(fp_line
			(start 0.12065 -0.2794)
			(end -0.12065 -0.2794)
			(stroke
				(width 0.1)
				(type default)
			)
			(layer "B.Fab")
		)
		(fp_line
			(start 0.12065 0.2794)
			(end 0.12065 0.3048)
			(stroke
				(width 0.1)
				(type default)
			)
			(layer "B.Fab")
		)
		(fp_line
			(start 0.12065 0.3048)
			(end 0.67945 0.3048)
			(stroke
				(width 0.1)
				(type default)
			)
			(layer "B.Fab")
		)
		(fp_line
			(start 0.67945 -0.305054)
			(end 0.12065 -0.305054)
			(stroke
				(width 0.1)
				(type default)
			)
			(layer "B.Fab")
		)
		(fp_line
			(start 0.67945 0.3048)
			(end 0.67945 -0.305054)
			(stroke
				(width 0.1)
				(type default)
			)
			(layer "B.Fab")
		)
		(pad "1" smd circle
			(at 0.40005 0 180)
			(size 0 0)
			(layers "B.Cu" "B.Mask" "B.Paste")
			(net "P3V3_AUX")
		)
		(pad "2" smd circle
			(at -0.40005 0 180)
			(size 0 0)
			(layers "B.Cu" "B.Mask" "B.Paste")
			(net "SMB_P52V_VPDB_SDA")
		)
	)
	(footprint ""
		(layer "B.Cu")
		(at 277.114 -100.203 90)
		(property "Reference" "PR220"
			(at 0 0 90)
			(layer "B.SilkS")
			(hide yes)
			(effects
				(font
					(size 1.27 1.27)
				)
				(justify mirror)
			)
		)
		(property "Value" ""
			(at 0 0 90)
			(layer "B.Fab")
			(effects
				(font
					(size 1.27 1.27)
				)
				(justify mirror)
			)
		)
		(duplicate_pad_numbers_are_jumpers no)
		(fp_line
			(start 1.2954 -0.5842)
			(end -1.2954 -0.5842)
			(stroke
				(width 0.1524)
				(type default)
			)
			(layer "B.SilkS")
		)
		(fp_line
			(start -1.2954 -0.5842)
			(end -1.2954 0.5842)
			(stroke
				(width 0.1524)
				(type default)
			)
			(layer "B.SilkS")
		)
		(fp_line
			(start 1.2954 0.5842)
			(end 1.2954 -0.5842)
			(stroke
				(width 0.1524)
				(type default)
			)
			(layer "B.SilkS")
		)
		(fp_line
			(start -1.2954 0.5842)
			(end 1.2954 0.5842)
			(stroke
				(width 0.1524)
				(type default)
			)
			(layer "B.SilkS")
		)
		(fp_line
			(start 0.8636 -0.4572)
			(end -0.8636 -0.4572)
			(stroke
				(width 0.1)
				(type default)
			)
			(layer "B.Fab")
		)
		(fp_line
			(start -0.8636 -0.4572)
			(end -0.8636 -0.406654)
			(stroke
				(width 0.1)
				(type default)
			)
			(layer "B.Fab")
		)
		(fp_line
			(start 1.1938 -0.406654)
			(end 0.8636 -0.406654)
			(stroke
				(width 0.1)
				(type default)
			)
			(layer "B.Fab")
		)
		(fp_line
			(start 0.8636 -0.406654)
			(end 0.8636 -0.4572)
			(stroke
				(width 0.1)
				(type default)
			)
			(layer "B.Fab")
		)
		(fp_line
			(start -0.8636 -0.406654)
			(end -1.1938 -0.406654)
			(stroke
				(width 0.1)
				(type default)
			)
			(layer "B.Fab")
		)
		(fp_line
			(start -1.1938 -0.406654)
			(end -1.1938 0.4064)
			(stroke
				(width 0.1)
				(type default)
			)
			(layer "B.Fab")
		)
		(fp_line
			(start 1.1938 0.4064)
			(end 1.1938 -0.406654)
			(stroke
				(width 0.1)
				(type default)
			)
			(layer "B.Fab")
		)
		(fp_line
			(start 0.8636 0.4064)
			(end 1.1938 0.4064)
			(stroke
				(width 0.1)
				(type default)
			)
			(layer "B.Fab")
		)
		(fp_line
			(start -0.8636 0.4064)
			(end -0.8636 0.4572)
			(stroke
				(width 0.1)
				(type default)
			)
			(layer "B.Fab")
		)
		(fp_line
			(start -1.1938 0.4064)
			(end -0.8636 0.4064)
			(stroke
				(width 0.1)
				(type default)
			)
			(layer "B.Fab")
		)
		(fp_line
			(start 0.8636 0.4318)
			(end 0.8636 0.4064)
			(stroke
				(width 0.1)
				(type default)
			)
			(layer "B.Fab")
		)
		(fp_line
			(start 0.8636 0.4572)
			(end 0.8636 0.4318)
			(stroke
				(width 0.1)
				(type default)
			)
			(layer "B.Fab")
		)
		(fp_line
			(start -0.8636 0.4572)
			(end 0.8636 0.4572)
			(stroke
				(width 0.1)
				(type default)
			)
			(layer "B.Fab")
		)
		(pad "1" smd rect
			(at 0.7366 0)
			(size 0.7112 0.8128)
			(layers "B.Cu" "B.Mask" "B.Paste")
			(net "P52V_HS1_4287_GATE_R")
		)
		(pad "2" smd rect
			(at -0.7366 0)
			(size 0.7112 0.8128)
			(layers "B.Cu" "B.Mask" "B.Paste")
			(net "P52V_HS1_GATE_RC")
		)
	)
	(footprint ""
		(layer "B.Cu")
		(at 276.733 -44.323)
		(property "Reference" "PR36"
			(at 0 0 0)
			(layer "B.SilkS")
			(hide yes)
			(effects
				(font
					(size 1.27 1.27)
				)
				(justify mirror)
			)
		)
		(property "Value" ""
			(at 0 0 0)
			(layer "B.Fab")
			(effects
				(font
					(size 1.27 1.27)
				)
				(justify mirror)
			)
		)
		(duplicate_pad_numbers_are_jumpers no)
		(fp_line
			(start -0.7874 -0.4064)
			(end -0.7874 0.4064)
			(stroke
				(width 0.1524)
				(type default)
			)
			(layer "B.SilkS")
		)
		(fp_line
			(start -0.7874 0.4064)
			(end 0.7874 0.4064)
			(stroke
				(width 0.1524)
				(type default)
			)
			(layer "B.SilkS")
		)
		(fp_line
			(start 0.7874 -0.4064)
			(end -0.7874 -0.4064)
			(stroke
				(width 0.1524)
				(type default)
			)
			(layer "B.SilkS")
		)
		(fp_line
			(start 0.7874 0.4064)
			(end 0.7874 -0.4064)
			(stroke
				(width 0.1524)
				(type default)
			)
			(layer "B.SilkS")
		)
		(fp_line
			(start -0.67945 -0.3048)
			(end -0.67945 0.3048)
			(stroke
				(width 0.1)
				(type default)
			)
			(layer "B.Fab")
		)
		(fp_line
			(start -0.67945 0.3048)
			(end -0.120396 0.3048)
			(stroke
				(width 0.1)
				(type default)
			)
			(layer "B.Fab")
		)
		(fp_line
			(start -0.12065 -0.3048)
			(end -0.67945 -0.3048)
			(stroke
				(width 0.1)
				(type default)
			)
			(layer "B.Fab")
		)
		(fp_line
			(start -0.12065 -0.2794)
			(end -0.12065 -0.3048)
			(stroke
				(width 0.1)
				(type default)
			)
			(layer "B.Fab")
		)
		(fp_line
			(start -0.120396 0.2794)
			(end 0.12065 0.2794)
			(stroke
				(width 0.1)
				(type default)
			)
			(layer "B.Fab")
		)
		(fp_line
			(start -0.120396 0.3048)
			(end -0.120396 0.2794)
			(stroke
				(width 0.1)
				(type default)
			)
			(layer "B.Fab")
		)
		(fp_line
			(start 0.12065 -0.305054)
			(end 0.12065 -0.2794)
			(stroke
				(width 0.1)
				(type default)
			)
			(layer "B.Fab")
		)
		(fp_line
			(start 0.12065 -0.2794)
			(end -0.12065 -0.2794)
			(stroke
				(width 0.1)
				(type default)
			)
			(layer "B.Fab")
		)
		(fp_line
			(start 0.12065 0.2794)
			(end 0.12065 0.3048)
			(stroke
				(width 0.1)
				(type default)
			)
			(layer "B.Fab")
		)
		(fp_line
			(start 0.12065 0.3048)
			(end 0.67945 0.3048)
			(stroke
				(width 0.1)
				(type default)
			)
			(layer "B.Fab")
		)
		(fp_line
			(start 0.67945 -0.305054)
			(end 0.12065 -0.305054)
			(stroke
				(width 0.1)
				(type default)
			)
			(layer "B.Fab")
		)
		(fp_line
			(start 0.67945 0.3048)
			(end 0.67945 -0.305054)
			(stroke
				(width 0.1)
				(type default)
			)
			(layer "B.Fab")
		)
		(pad "1" smd circle
			(at 0.40005 0 180)
			(size 0 0)
			(layers "B.Cu" "B.Mask" "B.Paste")
			(net "P52V_HS1_ESTART")
		)
		(pad "2" smd circle
			(at -0.40005 0 180)
			(size 0 0)
			(layers "B.Cu" "B.Mask" "B.Paste")
			(net "GND_FIELD_SIGNAL")
		)
	)
)
